(kicad_pcb
	(version 20260206)
	(generator "pcbnew")
	(generator_version "10.0")
	(general
		(thickness 1.6)
		(legacy_teardrops no)
	)
	(paper "A4")
	(title_block
		(title "dpb — 14545-sa.0730WZS0815.brd")
		(comment 1 "Honey Badger (Wiwynn) / footprints 439-441 of 1066")
	)
	(layers
		(0 "F.Cu" signal "TOP")
		(4 "In1.Cu" signal "L2GND")
		(6 "In2.Cu" signal "L3")
		(8 "In3.Cu" signal "L4VCC")
		(10 "In4.Cu" signal "L5VCC")
		(12 "In5.Cu" signal "L6")
		(14 "In6.Cu" signal "L7GND")
		(2 "B.Cu" signal "BOTTOM")
		(9 "F.Adhes" user "F.Adhesive")
		(11 "B.Adhes" user "B.Adhesive")
		(13 "F.Paste" user "Package Geometry/Pastemask Top")
		(15 "B.Paste" user "Package Geometry/Pastemask Bottom")
		(5 "F.SilkS" user "Ref Des/Silkscreen Top")
		(7 "B.SilkS" user "Ref Des/Silkscreen Bottom")
		(1 "F.Mask" user "Board Geometry/Soldermask Top")
		(3 "B.Mask" user "Board Geometry/Soldermask Bottom")
		(17 "Dwgs.User" user "User.Drawings")
		(19 "Cmts.User" user "User.Comments")
		(21 "Eco1.User" user "User.Eco1")
		(23 "Eco2.User" user "User.Eco2")
		(25 "Edge.Cuts" user "Board Geometry/Outline")
		(27 "Margin" user)
		(31 "F.CrtYd" user "Package Geometry/Place Bound Top")
		(29 "B.CrtYd" user "Package Geometry/Place Bound Bottom")
		(35 "F.Fab" user "Ref Des/Assembly Top")
		(33 "B.Fab" user "Ref Des/Assembly Bottom")
	)
	(footprint ""
		(layer "F.Cu")
		(at 17.500092 -232.32999 -90)
		(property "Reference" "SKT13"
			(at 0 0 270)
			(layer "F.SilkS")
			(hide yes)
			(effects
				(font
					(size 1.27 1.27)
				)
			)
		)
		(property "Value" "SKT-SATA14P-15P-12-GP"
			(at -22.6187 8.1788 270)
			(unlocked yes)
			(layer "F.Fab")
			(hide yes)
			(effects
				(font
					(size 1.016 1.016)
					(thickness 0.1524)
				)
			)
		)
		(property "Device Type" "87945-1001"
			(at -22.6187 6.6548 270)
			(unlocked yes)
			(layer "F.Fab")
			(hide yes)
			(effects
				(font
					(size 1.016 1.016)
					(thickness 0.1524)
				)
			)
		)
		(duplicate_pad_numbers_are_jumpers no)
		(fp_line
			(start -20.4724 9.652)
			(end -20.4724 2.3114)
			(stroke
				(width 0.1524)
				(type default)
			)
			(layer "F.SilkS")
		)
		(fp_line
			(start -17.8435 9.652)
			(end -20.4724 9.652)
			(stroke
				(width 0.1524)
				(type default)
			)
			(layer "F.SilkS")
		)
		(fp_line
			(start 17.8435 9.652)
			(end 17.8435 7.9502)
			(stroke
				(width 0.1524)
				(type default)
			)
			(layer "F.SilkS")
		)
		(fp_line
			(start 20.4724 9.652)
			(end 17.8435 9.652)
			(stroke
				(width 0.1524)
				(type default)
			)
			(layer "F.SilkS")
		)
		(fp_line
			(start -17.8435 7.9502)
			(end -17.8435 9.652)
			(stroke
				(width 0.1524)
				(type default)
			)
			(layer "F.SilkS")
		)
		(fp_line
			(start 17.8435 7.9502)
			(end -17.8435 7.9502)
			(stroke
				(width 0.1524)
				(type default)
			)
			(layer "F.SilkS")
		)
		(fp_line
			(start -23.7617 2.3114)
			(end -23.7617 -2.3114)
			(stroke
				(width 0.1524)
				(type default)
			)
			(layer "F.SilkS")
		)
		(fp_line
			(start -20.4724 2.3114)
			(end -23.7617 2.3114)
			(stroke
				(width 0.1524)
				(type default)
			)
			(layer "F.SilkS")
		)
		(fp_line
			(start 20.4724 2.3114)
			(end 20.4724 9.652)
			(stroke
				(width 0.1524)
				(type default)
			)
			(layer "F.SilkS")
		)
		(fp_line
			(start 23.7617 2.3114)
			(end 20.4724 2.3114)
			(stroke
				(width 0.1524)
				(type default)
			)
			(layer "F.SilkS")
		)
		(fp_line
			(start -23.117556 0.5461)
			(end -23.117556 -0.5461)
			(stroke
				(width 0.3048)
				(type default)
			)
			(layer "F.SilkS")
		)
		(fp_line
			(start 20.882356 0.5461)
			(end 20.882356 -0.5461)
			(stroke
				(width 0.3048)
				(type default)
			)
			(layer "F.SilkS")
		)
		(fp_line
			(start -20.882356 -0.5461)
			(end -20.882356 0.5461)
			(stroke
				(width 0.3048)
				(type default)
			)
			(layer "F.SilkS")
		)
		(fp_line
			(start 23.117556 -0.5461)
			(end 23.117556 0.5461)
			(stroke
				(width 0.3048)
				(type default)
			)
			(layer "F.SilkS")
		)
		(fp_line
			(start -23.7617 -2.3114)
			(end -20.4724 -2.3114)
			(stroke
				(width 0.1524)
				(type default)
			)
			(layer "F.SilkS")
		)
		(fp_line
			(start -20.4724 -2.3114)
			(end -20.4724 -5.7658)
			(stroke
				(width 0.1524)
				(type default)
			)
			(layer "F.SilkS")
		)
		(fp_line
			(start 20.4724 -2.3114)
			(end 23.7617 -2.3114)
			(stroke
				(width 0.1524)
				(type default)
			)
			(layer "F.SilkS")
		)
		(fp_line
			(start 23.7617 -2.3114)
			(end 23.7617 2.3114)
			(stroke
				(width 0.1524)
				(type default)
			)
			(layer "F.SilkS")
		)
		(fp_line
			(start -20.4724 -5.7658)
			(end 20.4724 -5.7658)
			(stroke
				(width 0.1524)
				(type default)
			)
			(layer "F.SilkS")
		)
		(fp_line
			(start 20.4724 -5.7658)
			(end 20.4724 -2.3114)
			(stroke
				(width 0.1524)
				(type default)
			)
			(layer "F.SilkS")
		)
		(fp_line
			(start -15.3924 -5.8547)
			(end -16.3576 -5.8547)
			(stroke
				(width 0.3302)
				(type default)
			)
			(layer "F.SilkS")
		)
		(fp_arc
			(start -20.882356 0.5461)
			(mid -21.999956 1.6637)
			(end -23.117556 0.5461)
			(stroke
				(width 0.3048)
				(type default)
			)
			(layer "F.SilkS")
		)
		(fp_arc
			(start 23.117556 0.5461)
			(mid 21.999956 1.6637)
			(end 20.882356 0.5461)
			(stroke
				(width 0.3048)
				(type default)
			)
			(layer "F.SilkS")
		)
		(fp_arc
			(start -23.117556 -0.5461)
			(mid -21.999956 -1.6637)
			(end -20.882356 -0.5461)
			(stroke
				(width 0.3048)
				(type default)
			)
			(layer "F.SilkS")
		)
		(fp_arc
			(start 20.882356 -0.5461)
			(mid 21.999956 -1.6637)
			(end 23.117556 -0.5461)
			(stroke
				(width 0.3048)
				(type default)
			)
			(layer "F.SilkS")
		)
		(fp_poly
			(pts
				(xy -15.87119 -5.838698) (xy -15.23619 -6.473698) (xy -16.50619 -6.473698)
			)
			(stroke
				(width 0)
				(type default)
			)
			(fill yes)
			(layer "F.SilkS")
		)
		(fp_poly
			(pts
				(xy -20.2184 -5.5118) (xy 20.2184 -5.5118) (xy 20.2184 -2.0574) (xy 23.5077 -2.0574) (xy 23.5077 2.0574)
				(xy 20.2184 2.0574) (xy 20.2184 9.398) (xy 18.0975 9.398) (xy 18.0975 7.6962) (xy -18.0975 7.6962)
				(xy -18.0975 9.398) (xy -20.2184 9.398) (xy -20.2184 2.0574) (xy -23.5077 2.0574) (xy -23.5077 -2.0574)
				(xy -20.2184 -2.0574)
			)
			(stroke
				(width 0)
				(type default)
			)
			(fill no)
			(layer "F.CrtYd")
		)
		(fp_poly
			(pts
				(xy -20.2184 -5.5118) (xy -20.2184 -6.0198) (xy -20.7264 -6.0198) (xy -20.7264 -2.5654) (xy -24.0157 -2.5654)
				(xy -24.0157 2.5654) (xy -20.7264 2.5654) (xy -20.7264 9.906) (xy -17.5895 9.906) (xy -17.5895 8.2042)
				(xy 17.5895 8.2042) (xy 17.5895 9.906) (xy 20.7264 9.906) (xy 20.7264 2.5654) (xy 24.0157 2.5654)
				(xy 24.0157 -2.5654) (xy 20.7264 -2.5654) (xy 20.7264 -6.0198) (xy -20.21586 -6.0198) (xy -20.21586 -5.5118)
				(xy 20.2184 -5.5118) (xy 20.2184 -2.0574) (xy 23.5077 -2.0574) (xy 23.5077 2.0574) (xy 20.2184 2.0574)
				(xy 20.2184 9.398) (xy 18.0975 9.398) (xy 18.0975 7.6962) (xy -18.0975 7.6962) (xy -18.0975 9.398)
				(xy -20.2184 9.398) (xy -20.2184 2.0574) (xy -23.5077 2.0574) (xy -23.5077 -2.0574) (xy -20.2184 -2.0574)
			)
			(stroke
				(width 0)
				(type default)
			)
			(fill no)
			(layer "F.CrtYd")
		)
		(fp_poly
			(pts
				(xy -20.7264 -6.0198) (xy -20.7264 -2.5654) (xy -24.0157 -2.5654) (xy -24.0157 2.5654) (xy -20.7264 2.5654)
				(xy -20.7264 9.906) (xy -17.5895 9.906) (xy -17.5895 8.2042) (xy 17.5895 8.2042) (xy 17.5895 9.906)
				(xy 20.7264 9.906) (xy 20.7264 2.5654) (xy 24.0157 2.5654) (xy 24.0157 -2.5654) (xy 20.7264 -2.5654)
				(xy 20.7264 -6.0198)
			)
			(stroke
				(width 0)
				(type default)
			)
			(fill no)
			(layer "F.Fab")
		)
		(pad "" np_thru_hole circle
			(at -18.999962 -2.350008 270)
			(size 0.254 0.254)
			(drill 1.8542)
			(layers "*.Cu" "*.Mask")
			(clearance 1.1557)
			(thermal_gap 1.1557)
		)
		(pad "" np_thru_hole circle
			(at 18.999962 -2.350008 270)
			(size 0.254 0.254)
			(drill 1.8542)
			(layers "*.Cu" "*.Mask")
			(clearance 1.1557)
			(thermal_gap 1.1557)
		)
		(pad "H1" thru_hole oval
			(at -21.999956 0 270)
			(size 1.524 2.6162)
			(drill oval 0.8128 1.905)
			(layers "*.Cu" "*.Mask")
			(remove_unused_layers no)
			(net "GND")
			(clearance 0.1524)
			(thermal_gap 0.1524)
		)
		(pad "H2" thru_hole oval
			(at 21.999956 0 270)
			(size 1.524 2.6162)
			(drill oval 0.8128 1.905)
			(layers "*.Cu" "*.Mask")
			(remove_unused_layers no)
			(net "GND")
			(clearance 0.1524)
			(thermal_gap 0.1524)
		)
		(pad "P1" smd rect
			(at -1.89992 -4.249928 270)
			(size 0.6604 2.3876)
			(layers "F.Cu" "F.Mask" "F.Paste")
			(net "Net_55")
		)
		(pad "P2" smd rect
			(at -0.62992 -4.249928 270)
			(size 0.6604 2.3876)
			(layers "F.Cu" "F.Mask" "F.Paste")
			(net "Net_54")
		)
		(pad "P3" smd rect
			(at 0.64008 -4.249928 270)
			(size 0.6604 2.3876)
			(layers "F.Cu" "F.Mask" "F.Paste")
			(net "Net_53")
		)
		(pad "P4" smd rect
			(at 1.91008 -4.249928 270)
			(size 0.6604 2.3876)
			(layers "F.Cu" "F.Mask" "F.Paste")
			(net "GND")
		)
		(pad "P5" smd rect
			(at 3.18008 -4.249928 270)
			(size 0.6604 2.3876)
			(layers "F.Cu" "F.Mask" "F.Paste")
			(net "HDD_PRSNT_NET12")
		)
		(pad "P6" smd rect
			(at 4.45008 -4.249928 270)
			(size 0.6604 2.3876)
			(layers "F.Cu" "F.Mask" "F.Paste")
			(net "GND")
		)
		(pad "P7" smd rect
			(at 5.72008 -4.249928 270)
			(size 0.6604 2.3876)
			(layers "F.Cu" "F.Mask" "F.Paste")
			(net "5V_PRE_12")
		)
		(pad "P8" smd rect
			(at 6.99008 -4.249928 270)
			(size 0.6604 2.3876)
			(layers "F.Cu" "F.Mask" "F.Paste")
			(net "P5V_HDD12")
		)
		(pad "P9" smd rect
			(at 8.26008 -4.249928 270)
			(size 0.6604 2.3876)
			(layers "F.Cu" "F.Mask" "F.Paste")
			(net "P5V_HDD12")
		)
		(pad "P10" smd rect
			(at 9.53008 -4.249928 270)
			(size 0.6604 2.3876)
			(layers "F.Cu" "F.Mask" "F.Paste")
			(net "GND")
		)
		(pad "P11" smd rect
			(at 10.80008 -4.249928 270)
			(size 0.6604 2.3876)
			(layers "F.Cu" "F.Mask" "F.Paste")
			(net "ACT_HDD12")
		)
		(pad "P12" smd rect
			(at 12.07008 -4.249928 270)
			(size 0.6604 2.3876)
			(layers "F.Cu" "F.Mask" "F.Paste")
			(net "GND")
		)
		(pad "P13" smd rect
			(at 13.34008 -4.249928 270)
			(size 0.6604 2.3876)
			(layers "F.Cu" "F.Mask" "F.Paste")
			(net "12V_PRE_12")
		)
		(pad "P14" smd rect
			(at 14.61008 -4.249928 270)
			(size 0.6604 2.3876)
			(layers "F.Cu" "F.Mask" "F.Paste")
			(net "P12V_HDD12")
		)
		(pad "P15" smd rect
			(at 15.88008 -4.249928 270)
			(size 0.6604 2.3876)
			(layers "F.Cu" "F.Mask" "F.Paste")
			(net "P12V_HDD12")
		)
		(pad "S1" smd rect
			(at -15.86992 -4.249928 270)
			(size 0.6604 2.3876)
			(layers "F.Cu" "F.Mask" "F.Paste")
			(net "GND")
		)
		(pad "S2" smd rect
			(at -14.59992 -4.249928 270)
			(size 0.6604 2.3876)
			(layers "F.Cu" "F.Mask" "F.Paste")
			(net "SAS2X28_A_HDD12_TX_+")
		)
		(pad "S3" smd rect
			(at -13.32992 -4.249928 270)
			(size 0.6604 2.3876)
			(layers "F.Cu" "F.Mask" "F.Paste")
			(net "SAS2X28_A_HDD12_TX_-")
		)
		(pad "S4" smd rect
			(at -12.05992 -4.249928 270)
			(size 0.6604 2.3876)
			(layers "F.Cu" "F.Mask" "F.Paste")
			(net "GND")
		)
		(pad "S5" smd rect
			(at -10.78992 -4.249928 270)
			(size 0.6604 2.3876)
			(layers "F.Cu" "F.Mask" "F.Paste")
			(net "SAS2X28_DRIVE_RX_N_A12")
		)
		(pad "S6" smd rect
			(at -9.51992 -4.249928 270)
			(size 0.6604 2.3876)
			(layers "F.Cu" "F.Mask" "F.Paste")
			(net "SAS2X28_DRIVE_RX_P_A12")
		)
		(pad "S7" smd rect
			(at -8.24992 -4.249928 270)
			(size 0.6604 2.3876)
			(layers "F.Cu" "F.Mask" "F.Paste")
			(net "GND")
		)
		(pad "S8" smd rect
			(at -7.480046 -2.100072 270)
			(size 0.508 1.905)
			(layers "F.Cu" "F.Mask" "F.Paste")
			(net "GND")
		)
		(pad "S9" smd rect
			(at -6.679946 -2.100072 270)
			(size 0.508 1.905)
			(layers "F.Cu" "F.Mask" "F.Paste")
			(net "SAS2X28_B_HDD12_TX_+")
		)
		(pad "S10" smd rect
			(at -5.8801 -2.100072 270)
			(size 0.508 1.905)
			(layers "F.Cu" "F.Mask" "F.Paste")
			(net "SAS2X28_B_HDD12_TX_-")
		)
		(pad "S11" smd rect
			(at -5.08 -2.100072 270)
			(size 0.508 1.905)
			(layers "F.Cu" "F.Mask" "F.Paste")
			(net "GND")
		)
		(pad "S12" smd rect
			(at -4.2799 -2.100072 270)
			(size 0.508 1.905)
			(layers "F.Cu" "F.Mask" "F.Paste")
			(net "SAS2X28_DRIVE_RX_N_B12")
		)
		(pad "S13" smd rect
			(at -3.480054 -2.100072 270)
			(size 0.508 1.905)
			(layers "F.Cu" "F.Mask" "F.Paste")
			(net "SAS2X28_DRIVE_RX_P_B12")
		)
		(pad "S14" smd rect
			(at -2.679954 -2.100072 270)
			(size 0.508 1.905)
			(layers "F.Cu" "F.Mask" "F.Paste")
			(net "GND")
		)
		(zone
			(layers "F.Cu" "B.Cu" "In1.Cu" "In2.Cu" "In3.Cu" "In4.Cu" "In5.Cu" "In6.Cu")
			(hatch none 0.5)
			(connect_pads
				(clearance 0)
			)
			(min_thickness 0.25)
			(keepout
				(tracks not_allowed)
				(vias allowed)
				(pads allowed)
				(copperpour not_allowed)
				(footprints allowed)
			)
			(placement
				(enabled no)
				(sheetname "")
			)
			(fill
				(thermal_gap 0.5)
				(thermal_bridge_width 0.5)
				(island_removal_mode 0)
			)
			(polygon
				(pts
					(arc
						(start 21.082 -251.329952)
						(mid 18.6182 -251.329952)
						(end 21.082 -251.329952)
					)
				)
			)
		)
		(zone
			(layers "F.Cu" "B.Cu" "In1.Cu" "In2.Cu" "In3.Cu" "In4.Cu" "In5.Cu" "In6.Cu")
			(hatch none 0.5)
			(connect_pads
				(clearance 0)
			)
			(min_thickness 0.25)
			(keepout
				(tracks not_allowed)
				(vias allowed)
				(pads allowed)
				(copperpour not_allowed)
				(footprints allowed)
			)
			(placement
				(enabled no)
				(sheetname "")
			)
			(fill
				(thermal_gap 0.5)
				(thermal_bridge_width 0.5)
				(island_removal_mode 0)
			)
			(polygon
				(pts
					(arc
						(start 21.082 -213.330028)
						(mid 18.6182 -213.330028)
						(end 21.082 -213.330028)
					)
				)
			)
		)
	)
	(footprint ""
		(layer "F.Cu")
		(at 30.226 -288.29 180)
		(property "Reference" "R556"
			(at 0 0 180)
			(layer "F.SilkS")
			(hide yes)
			(effects
				(font
					(size 1.27 1.27)
				)
			)
		)
		(property "Value" "200KR2F-L-GP"
			(at 0.064008 -3.993896 180)
			(unlocked yes)
			(layer "F.Fab")
			(hide yes)
			(effects
				(font
					(size 1.016 1.016)
					(thickness 0.1524)
				)
			)
		)
		(property "Device Type" "R402H16"
			(at 0.064008 -5.517896 180)
			(unlocked yes)
			(layer "F.Fab")
			(hide yes)
			(effects
				(font
					(size 1.016 1.016)
					(thickness 0.1524)
				)
			)
		)
		(duplicate_pad_numbers_are_jumpers no)
		(fp_line
			(start 0.508 -0.9398)
			(end -0.508 -0.9398)
			(stroke
				(width 0.1524)
				(type default)
			)
			(layer "F.SilkS")
		)
		(fp_line
			(start -0.508 -0.9398)
			(end -0.508 0.9398)
			(stroke
				(width 0.1524)
				(type default)
			)
			(layer "F.SilkS")
		)
		(fp_rect
			(start -0.508 0.9398)
			(end 0.508 -0.9398)
			(stroke
				(width 0)
				(type default)
			)
			(fill no)
			(layer "F.CrtYd")
		)
		(fp_rect
			(start -0.508 0.9398)
			(end 0.508 -0.9398)
			(stroke
				(width 0)
				(type default)
			)
			(fill no)
			(layer "F.Fab")
		)
		(pad "1" smd custom
			(at 0 -0.4445 180)
			(size 0.1397 0.1397)
			(layers "F.Cu" "F.Mask" "F.Paste")
			(net "SW_HDD7_R")
			(options
				(clearance outline)
				(anchor circle)
			)
			(primitives
				(gr_poly
					(pts
						(arc
							(start -0.1778 -0.2794)
							(mid -0.249642 -0.249642)
							(end -0.2794 -0.1778)
						)
						(arc
							(start -0.2794 0.1778)
							(mid -0.249642 0.249642)
							(end -0.1778 0.2794)
						)
						(arc
							(start 0.1778 0.2794)
							(mid 0.249642 0.249642)
							(end 0.2794 0.1778)
						)
						(arc
							(start 0.2794 -0.1778)
							(mid 0.249642 -0.249642)
							(end 0.1778 -0.2794)
						)
					)
					(width 0)
					(fill yes)
				)
			)
		)
		(pad "2" smd custom
			(at 0 0.4445 180)
			(size 0.1397 0.1397)
			(layers "F.Cu" "F.Mask" "F.Paste")
			(net "SW_HDD7_N")
			(options
				(clearance outline)
				(anchor circle)
			)
			(primitives
				(gr_poly
					(pts
						(arc
							(start -0.1778 -0.2794)
							(mid -0.249642 -0.249642)
							(end -0.2794 -0.1778)
						)
						(arc
							(start -0.2794 0.1778)
							(mid -0.249642 0.249642)
							(end -0.1778 0.2794)
						)
						(arc
							(start 0.1778 0.2794)
							(mid 0.249642 0.249642)
							(end 0.2794 0.1778)
						)
						(arc
							(start 0.2794 -0.1778)
							(mid 0.249642 -0.249642)
							(end 0.1778 -0.2794)
						)
					)
					(width 0)
					(fill yes)
				)
			)
		)
	)
	(footprint ""
		(layer "F.Cu")
		(at 21.971 -278.765 -90)
		(property "Reference" "C219"
			(at 0 0 270)
			(layer "F.SilkS")
			(hide yes)
			(effects
				(font
					(size 1.27 1.27)
				)
			)
		)
		(property "Value" "SCD1U10V2KX-5GP"
			(at 1.1811 -2.7051 270)
			(unlocked yes)
			(layer "F.Fab")
			(hide yes)
			(effects
				(font
					(size 1.016 1.016)
					(thickness 0.1524)
				)
			)
		)
		(property "Device Type" "C402H22"
			(at 1.1811 -4.2291 270)
			(unlocked yes)
			(layer "F.Fab")
			(hide yes)
			(effects
				(font
					(size 1.016 1.016)
					(thickness 0.1524)
				)
			)
		)
		(duplicate_pad_numbers_are_jumpers no)
		(fp_rect
			(start -0.4318 0.9525)
			(end 0.4318 -0.9525)
			(stroke
				(width 0)
				(type default)
			)
			(fill no)
			(layer "F.CrtYd")
		)
		(fp_rect
			(start -0.4318 0.9525)
			(end 0.4318 -0.9525)
			(stroke
				(width 0)
				(type default)
			)
			(fill no)
			(layer "F.Fab")
		)
		(pad "1" smd custom
			(at 0 -0.4445 270)
			(size 0.1524 0.1524)
			(layers "F.Cu" "F.Mask" "F.Paste")
			(net "P3V3")
			(options
				(clearance outline)
				(anchor circle)
			)
			(primitives
				(gr_poly
					(pts
						(arc
							(start 0.3048 -0.2032)
							(mid 0.275042 -0.275042)
							(end 0.2032 -0.3048)
						)
						(arc
							(start -0.2032 -0.3048)
							(mid -0.275042 -0.275042)
							(end -0.3048 -0.2032)
						)
						(arc
							(start -0.3048 0.2032)
							(mid -0.275042 0.275042)
							(end -0.2032 0.3048)
						)
						(arc
							(start 0.2032 0.3048)
							(mid 0.275042 0.275042)
							(end 0.3048 0.2032)
						)
					)
					(width 0)
					(fill yes)
				)
			)
		)
		(pad "2" smd custom
			(at 0 0.4445 270)
			(size 0.1524 0.1524)
			(layers "F.Cu" "F.Mask" "F.Paste")
			(net "GND")
			(options
				(clearance outline)
				(anchor circle)
			)
			(primitives
				(gr_poly
					(pts
						(arc
							(start 0.3048 -0.2032)
							(mid 0.275042 -0.275042)
							(end 0.2032 -0.3048)
						)
						(arc
							(start -0.2032 -0.3048)
							(mid -0.275042 -0.275042)
							(end -0.3048 -0.2032)
						)
						(arc
							(start -0.3048 0.2032)
							(mid -0.275042 0.275042)
							(end -0.2032 0.3048)
						)
						(arc
							(start 0.2032 0.3048)
							(mid 0.275042 0.275042)
							(end 0.3048 0.2032)
						)
					)
					(width 0)
					(fill yes)
				)
			)
		)
	)
)
